# BASEBOARD_FAB2 (Tioga Pass) — schematic netlist excerpt (pin names and nets, part order shuffled) for the footprints in the layout excerpt that follows; sources: Cadence DE-HDL packaged netlist, KiCad conversion of Wiwynn_Tioga_Pass_MB.brd

R25W95  RES  4.75K 1% CHIP  pkg 0402  page 150 : A = P3V3_STBY ; B = SPI_BMC_BT_CLK
FB7B1  FERRITE  22 1% FB  pkg SM  page 232 : A = P12V_STBY ; B = VR_FET_SW_P12V_STBY_PVPP_DEF
C6B15  CAP  0.22UF 16V 10% X7R  pkg 0402  page 105 : A = P3E_CPU0_PE1_PCH_TXN<10> ; B = P3E_CPU0_PE1_PCH_C_TXN<10>

(kicad_pcb
	(version 20260206)
	(generator "pcbnew")
	(generator_version "10.0")
	(general
		(thickness 1.6)
		(legacy_teardrops no)
	)
	(paper "A4")
	(title_block
		(title "Wiwynn_Tioga_Pass_MB.brd")
		(comment 1 "Tioga Pass / footprints 1217-1219 of 4770")
	)
	(layers
		(0 "F.Cu" signal "TOP")
		(4 "In1.Cu" signal "L2GND")
		(6 "In2.Cu" signal "L3")
		(8 "In3.Cu" signal "L4GND")
		(10 "In4.Cu" signal "L5")
		(12 "In5.Cu" signal "L6GND")
		(14 "In6.Cu" signal "L7VCC")
		(16 "In7.Cu" signal "L8VCC")
		(18 "In8.Cu" signal "L9GND")
		(20 "In9.Cu" signal "L10")
		(22 "In10.Cu" signal "L11GND")
		(24 "In11.Cu" signal "L12")
		(26 "In12.Cu" signal "L13GND")
		(2 "B.Cu" signal "BOTTOM")
		(9 "F.Adhes" user "F.Adhesive")
		(11 "B.Adhes" user "B.Adhesive")
		(13 "F.Paste" user "Package Geometry/Pastemask Top")
		(15 "B.Paste" user "Package Geometry/Pastemask Bottom")
		(5 "F.SilkS" user "Ref Des/Silkscreen Top")
		(7 "B.SilkS" user "Ref Des/Silkscreen Bottom")
		(1 "F.Mask" user "Board Geometry/Soldermask Top")
		(3 "B.Mask" user "Board Geometry/Soldermask Bottom")
		(17 "Dwgs.User" user "User.Drawings")
		(19 "Cmts.User" user "User.Comments")
		(21 "Eco1.User" user "User.Eco1")
		(23 "Eco2.User" user "User.Eco2")
		(25 "Edge.Cuts" user "Board Geometry/Outline")
		(27 "Margin" user)
		(31 "F.CrtYd" user "Package Geometry/Place Bound Top")
		(29 "B.CrtYd" user "Package Geometry/Place Bound Bottom")
		(35 "F.Fab" user "Ref Des/Assembly Top")
		(33 "B.Fab" user "Ref Des/Assembly Bottom")
	)
	(footprint ""
		(layer "F.Cu")
		(at 351.663 -135.001)
		(property "Reference" "FB7B1"
			(at 0 0 0)
			(layer "F.SilkS")
			(hide yes)
			(effects
				(font
					(size 1.27 1.27)
				)
			)
		)
		(property "Value" ""
			(at 0 0 0)
			(layer "F.Fab")
			(effects
				(font
					(size 1.27 1.27)
				)
			)
		)
		(duplicate_pad_numbers_are_jumpers no)
		(fp_poly
			(pts
				(xy -0.7239 -0.26035) (xy 0.7239 -0.26035) (xy 0.7239 2.03835) (xy -0.7239 2.03835)
			)
			(stroke
				(width 0)
				(type default)
			)
			(fill no)
			(layer "F.CrtYd")
		)
		(fp_line
			(start -0.7239 -0.26035)
			(end 0.7239 -0.26035)
			(stroke
				(width 0.1)
				(type default)
			)
			(layer "F.Fab")
		)
		(fp_line
			(start -0.7239 2.03835)
			(end -0.7239 -0.26035)
			(stroke
				(width 0.1)
				(type default)
			)
			(layer "F.Fab")
		)
		(fp_line
			(start 0.7239 -0.26035)
			(end 0.7239 2.03835)
			(stroke
				(width 0.1)
				(type default)
			)
			(layer "F.Fab")
		)
		(fp_line
			(start 0.7239 2.03835)
			(end -0.7239 2.03835)
			(stroke
				(width 0.1)
				(type default)
			)
			(layer "F.Fab")
		)
		(pad "1" smd rect
			(at 0 0)
			(size 1.27 1.016)
			(layers "F.Cu" "F.Mask" "F.Paste")
			(net "P12V_STBY")
		)
		(pad "2" smd rect
			(at 0 1.778)
			(size 1.27 1.016)
			(layers "F.Cu" "F.Mask" "F.Paste")
			(net "VR_FET_SW_P12V_STBY_PVPP_DEF")
		)
		(zone
			(layer "F.Cu")
			(hatch none 0.5)
			(connect_pads
				(clearance 0)
			)
			(min_thickness 0.25)
			(keepout
				(tracks not_allowed)
				(vias allowed)
				(pads allowed)
				(copperpour not_allowed)
				(footprints allowed)
			)
			(placement
				(enabled no)
				(sheetname "")
			)
			(fill
				(thermal_gap 0.5)
				(thermal_bridge_width 0.5)
				(island_removal_mode 0)
			)
			(polygon
				(pts
					(xy 352.298 -134.493) (xy 352.298 -133.731) (xy 352.2091 -133.731) (xy 351.028 -133.731) (xy 351.028 -134.493)
				)
			)
		)
	)
	(footprint ""
		(layer "F.Cu")
		(at 432.6509 -45.1739)
		(property "Reference" "R25W95"
			(at -0.8382 -0.67818 0)
			(unlocked yes)
			(layer "F.SilkS")
			(effects
				(font
					(size 0.4064 0.254)
					(thickness 0.1524)
				)
				(justify left)
			)
		)
		(property "Value" ""
			(at 0 0 0)
			(layer "F.Fab")
			(effects
				(font
					(size 1.27 1.27)
				)
			)
		)
		(duplicate_pad_numbers_are_jumpers no)
		(fp_poly
			(pts
				(xy -0.2794 -0.1016) (xy 0.2794 -0.1016) (xy 0.2794 0.9906) (xy -0.2794 0.9906)
			)
			(stroke
				(width 0)
				(type default)
			)
			(fill no)
			(layer "F.CrtYd")
		)
		(fp_line
			(start -0.2794 -0.1016)
			(end -0.2794 0.9906)
			(stroke
				(width 0.1)
				(type default)
			)
			(layer "F.Fab")
		)
		(fp_line
			(start -0.2794 0.9906)
			(end 0.2794 0.9906)
			(stroke
				(width 0.1)
				(type default)
			)
			(layer "F.Fab")
		)
		(fp_line
			(start 0.2794 -0.1016)
			(end -0.2794 -0.1016)
			(stroke
				(width 0.1)
				(type default)
			)
			(layer "F.Fab")
		)
		(fp_line
			(start 0.2794 0.9906)
			(end 0.2794 -0.1016)
			(stroke
				(width 0.1)
				(type default)
			)
			(layer "F.Fab")
		)
		(pad "1" smd rect
			(at 0 0)
			(size 0.508 0.508)
			(layers "F.Cu" "F.Mask" "F.Paste")
			(net "P3V3_STBY")
		)
		(pad "2" smd rect
			(at 0 0.889)
			(size 0.508 0.508)
			(layers "F.Cu" "F.Mask" "F.Paste")
			(net "SPI_BMC_BT_CLK")
		)
		(zone
			(layer "F.Cu")
			(hatch none 0.5)
			(connect_pads
				(clearance 0)
			)
			(min_thickness 0.25)
			(keepout
				(tracks allowed)
				(vias not_allowed)
				(pads allowed)
				(copperpour not_allowed)
				(footprints allowed)
			)
			(placement
				(enabled no)
				(sheetname "")
			)
			(fill
				(thermal_gap 0.5)
				(thermal_bridge_width 0.5)
				(island_removal_mode 0)
			)
			(polygon
				(pts
					(xy 432.3969 -44.9199) (xy 432.9049 -44.9199) (xy 432.9049 -44.5389) (xy 432.3969 -44.5389)
				)
			)
		)
		(zone
			(layer "F.Cu")
			(hatch none 0.5)
			(connect_pads
				(clearance 0)
			)
			(min_thickness 0.25)
			(keepout
				(tracks not_allowed)
				(vias allowed)
				(pads allowed)
				(copperpour not_allowed)
				(footprints allowed)
			)
			(placement
				(enabled no)
				(sheetname "")
			)
			(fill
				(thermal_gap 0.5)
				(thermal_bridge_width 0.5)
				(island_removal_mode 0)
			)
			(polygon
				(pts
					(xy 432.3969 -44.5389) (xy 432.9049 -44.5389) (xy 432.9049 -44.9199) (xy 432.3969 -44.9199)
				)
			)
		)
	)
	(footprint ""
		(layer "F.Cu")
		(at 337.404202 -121.282968 90)
		(property "Reference" "C6B15"
			(at -0.8382 -0.67818 90)
			(unlocked yes)
			(layer "F.SilkS")
			(effects
				(font
					(size 0.4064 0.254)
					(thickness 0.1524)
				)
				(justify left)
			)
		)
		(property "Value" ""
			(at 0 0 90)
			(layer "F.Fab")
			(effects
				(font
					(size 1.27 1.27)
				)
			)
		)
		(duplicate_pad_numbers_are_jumpers no)
		(fp_poly
			(pts
				(xy 0.3048 -0.1016) (xy 0.3048 0.9906) (xy -0.3048 0.9906) (xy -0.3048 -0.1016)
			)
			(stroke
				(width 0)
				(type default)
			)
			(fill no)
			(layer "F.CrtYd")
		)
		(fp_line
			(start 0.3048 -0.1016)
			(end -0.3048 -0.1016)
			(stroke
				(width 0.1)
				(type default)
			)
			(layer "F.Fab")
		)
		(fp_line
			(start -0.3048 -0.1016)
			(end -0.3048 0.9906)
			(stroke
				(width 0.1)
				(type default)
			)
			(layer "F.Fab")
		)
		(fp_line
			(start 0.3048 0.9906)
			(end 0.3048 -0.1016)
			(stroke
				(width 0.1)
				(type default)
			)
			(layer "F.Fab")
		)
		(fp_line
			(start -0.3048 0.9906)
			(end 0.3048 0.9906)
			(stroke
				(width 0.1)
				(type default)
			)
			(layer "F.Fab")
		)
		(pad "1" smd rect
			(at 0 0 90)
			(size 0.508 0.508)
			(layers "F.Cu" "F.Mask" "F.Paste")
			(net "P3E_CPU0_PE1_PCH_TXN<10>")
		)
		(pad "2" smd rect
			(at 0 0.889 90)
			(size 0.508 0.508)
			(layers "F.Cu" "F.Mask" "F.Paste")
			(net "P3E_CPU0_PE1_PCH_C_TXN<10>")
		)
		(zone
			(layer "F.Cu")
			(hatch none 0.5)
			(connect_pads
				(clearance 0)
			)
			(min_thickness 0.25)
			(keepout
				(tracks allowed)
				(vias not_allowed)
				(pads allowed)
				(copperpour not_allowed)
				(footprints allowed)
			)
			(placement
				(enabled no)
				(sheetname "")
			)
			(fill
				(thermal_gap 0.5)
				(thermal_bridge_width 0.5)
				(island_removal_mode 0)
			)
			(polygon
				(pts
					(xy 337.658202 -121.028968) (xy 337.658202 -121.536968) (xy 338.039202 -121.536968) (xy 338.039202 -121.028968)
				)
			)
		)
		(zone
			(layer "F.Cu")
			(hatch none 0.5)
			(connect_pads
				(clearance 0)
			)
			(min_thickness 0.25)
			(keepout
				(tracks not_allowed)
				(vias allowed)
				(pads allowed)
				(copperpour not_allowed)
				(footprints allowed)
			)
			(placement
				(enabled no)
				(sheetname "")
			)
			(fill
				(thermal_gap 0.5)
				(thermal_bridge_width 0.5)
				(island_removal_mode 0)
			)
			(polygon
				(pts
					(xy 338.039202 -121.028968) (xy 338.039202 -121.536968) (xy 337.658202 -121.536968) (xy 337.658202 -121.028968)
				)
			)
		)
	)
)
